# TIMECARD (Time Appliance Project (Time Card)) — schematic netlist excerpt (pin names and nets, part order shuffled) for the footprints in the layout excerpt that follows; sources: Cadence DE-HDL packaged netlist, KiCad conversion of R4006-B0001-02_R01.brd

J4  CONN_JACK_1P_GH4_S_TH  2081680-1  pkg P_F_JACK_1P_GH4_RA_P200  page 23
  \1\  = SMA2_SIG_IO_CONN
  GH1  = SG
  GH2  = SG
  GH3  = SG
  GH4  = SG

(kicad_pcb
	(version 20260206)
	(generator "pcbnew")
	(generator_version "10.0")
	(general
		(thickness 1.6)
		(legacy_teardrops no)
	)
	(paper "A4")
	(title_block
		(title "timecard-production-celestica-r4006 — R4006-B0001-02_R01.brd")
		(comment 1 "Time Appliance Project (Time Card) / footprints 253-253 of 1113")
	)
	(layers
		(0 "F.Cu" signal "TOP")
		(4 "In1.Cu" signal "L02_GND1")
		(6 "In2.Cu" signal "L03_SIG1")
		(8 "In3.Cu" signal "L04_GND2")
		(10 "In4.Cu" signal "L05_VCC1")
		(12 "In5.Cu" signal "L06_VCC2")
		(14 "In6.Cu" signal "L07_GND3")
		(16 "In7.Cu" signal "L08_SIG2")
		(18 "In8.Cu" signal "L09_GND4")
		(2 "B.Cu" signal "BOTTOM")
		(9 "F.Adhes" user "F.Adhesive")
		(11 "B.Adhes" user "B.Adhesive")
		(13 "F.Paste" user "Package Geometry/Pastemask Top")
		(15 "B.Paste" user "Package Geometry/Pastemask Bottom")
		(5 "F.SilkS" user "Ref Des/Silkscreen Top")
		(7 "B.SilkS" user "Ref Des/Silkscreen Bottom")
		(1 "F.Mask" user "Board Geometry/Soldermask Top")
		(3 "B.Mask" user "Board Geometry/Soldermask Bottom")
		(17 "Dwgs.User" user "User.Drawings")
		(19 "Cmts.User" user "User.Comments")
		(21 "Eco1.User" user "User.Eco1")
		(23 "Eco2.User" user "User.Eco2")
		(25 "Edge.Cuts" user "Board Geometry/Outline")
		(27 "Margin" user)
		(31 "F.CrtYd" user "Package Geometry/Place Bound Top")
		(29 "B.CrtYd" user "Package Geometry/Place Bound Bottom")
		(35 "F.Fab" user "Ref Des/Assembly Top")
		(33 "B.Fab" user "Ref Des/Assembly Bottom")
	)
	(footprint ""
		(layer "F.Cu")
		(at 4.073906 -47.099982)
		(property "Reference" "J4"
			(at 4.816094 -2.390648 0)
			(unlocked yes)
			(layer "F.SilkS")
			(effects
				(font
					(size 0.7874 0.5842)
					(thickness 0.1524)
				)
			)
		)
		(property "Value" ""
			(at 0 0 0)
			(layer "F.Fab")
			(effects
				(font
					(size 1.27 1.27)
				)
			)
		)
		(property "Device Type" "CONN_JACK_1P_GH4_S_TH-G200-130A"
			(at -5.098288 5.899912 0)
			(unlocked yes)
			(layer "F.Fab")
			(hide yes)
			(effects
				(font
					(size 0.7874 0.5842)
					(thickness 0.1524)
				)
			)
		)
		(property "User Part Number" "PARTNUM*"
			(at -5.098288 7.093712 0)
			(unlocked yes)
			(layer "Cmts.User")
			(hide yes)
			(effects
				(font
					(size 0.7874 0.5842)
					(thickness 0.1524)
				)
			)
		)
		(duplicate_pad_numbers_are_jumpers no)
		(fp_line
			(start -13.953998 -3.937)
			(end 3.937 -3.937)
			(stroke
				(width 0.1)
				(type default)
			)
			(layer "F.SilkS")
		)
		(fp_line
			(start -13.953998 3.937)
			(end -13.953998 -3.937)
			(stroke
				(width 0.1)
				(type default)
			)
			(layer "F.SilkS")
		)
		(fp_line
			(start 3.937 -3.937)
			(end 3.937 3.937)
			(stroke
				(width 0.1)
				(type default)
			)
			(layer "F.SilkS")
		)
		(fp_line
			(start 3.937 3.937)
			(end -13.953998 3.937)
			(stroke
				(width 0.1)
				(type default)
			)
			(layer "F.SilkS")
		)
		(fp_rect
			(start -8.763 8.763)
			(end 8.763 -8.763)
			(stroke
				(width 0)
				(type default)
			)
			(fill no)
			(layer "B.CrtYd")
		)
		(fp_rect
			(start -14.207998 4.191)
			(end 4.191 -4.191)
			(stroke
				(width 0)
				(type default)
			)
			(fill no)
			(layer "F.CrtYd")
		)
		(fp_line
			(start -13.699998 -3.599942)
			(end 3.599942 -3.599942)
			(stroke
				(width 0.1)
				(type default)
			)
			(layer "F.Fab")
		)
		(fp_line
			(start -13.699998 3.599942)
			(end -13.699998 -3.599942)
			(stroke
				(width 0.1)
				(type default)
			)
			(layer "F.Fab")
		)
		(fp_line
			(start 3.599942 -3.599942)
			(end 3.599942 3.599942)
			(stroke
				(width 0.1)
				(type default)
			)
			(layer "F.Fab")
		)
		(fp_line
			(start 3.599942 3.599942)
			(end -13.699998 3.599942)
			(stroke
				(width 0.1)
				(type default)
			)
			(layer "F.Fab")
		)
		(fp_text user "GH3"
			(at -1.660906 4.332732 0)
			(unlocked yes)
			(layer "F.SilkS")
			(effects
				(font
					(size 0.635 0.4064)
					(thickness 0.1524)
				)
			)
		)
		(fp_text user "GH1"
			(at -0.263906 -4.227068 0)
			(unlocked yes)
			(layer "F.SilkS")
			(effects
				(font
					(size 0.635 0.4064)
					(thickness 0.1524)
				)
			)
		)
		(fp_text user "GH2"
			(at 2.911094 -4.354068 0)
			(unlocked yes)
			(layer "F.SilkS")
			(effects
				(font
					(size 0.635 0.4064)
					(thickness 0.1524)
				)
			)
		)
		(fp_text user "1"
			(at 4.015994 -0.104648 0)
			(unlocked yes)
			(layer "F.SilkS")
			(effects
				(font
					(size 0.7874 0.5842)
					(thickness 0.1524)
				)
				(justify left)
			)
		)
		(fp_text user "GH4"
			(at 4.466844 3.284982 90)
			(unlocked yes)
			(layer "F.SilkS")
			(effects
				(font
					(size 0.635 0.4064)
					(thickness 0.1524)
				)
			)
		)
		(fp_text user "GH1"
			(at -2.549906 -4.295648 0)
			(unlocked yes)
			(layer "F.Fab")
			(effects
				(font
					(size 0.7874 0.5842)
					(thickness 0.1524)
				)
			)
		)
		(fp_text user "GH3"
			(at -2.549906 4.215638 0)
			(unlocked yes)
			(layer "F.Fab")
			(effects
				(font
					(size 0.7874 0.5842)
					(thickness 0.1524)
				)
			)
		)
		(fp_text user "GH2"
			(at 2.149094 -4.168648 0)
			(unlocked yes)
			(layer "F.Fab")
			(effects
				(font
					(size 0.7874 0.5842)
					(thickness 0.1524)
				)
			)
		)
		(fp_text user "GH4"
			(at 2.54 4.64947 0)
			(unlocked yes)
			(layer "F.Fab")
			(effects
				(font
					(size 0.7874 0.5842)
					(thickness 0.1524)
				)
			)
		)
		(fp_text user "1"
			(at 3.800094 -0.356362 0)
			(unlocked yes)
			(layer "F.Fab")
			(effects
				(font
					(size 0.7874 0.5842)
					(thickness 0.1524)
				)
				(justify left)
			)
		)
		(pad "1" thru_hole circle
			(at 0 0)
			(size 2.1844 2.1844)
			(drill 1.4986)
			(layers "*.Cu" "*.Mask")
			(remove_unused_layers no)
			(net "SMA2_SIG_IO_CONN")
			(padstack
				(mode front_inner_back)
				(layer "Inner"
					(shape circle)
					(size 2.1844 2.1844)
					(clearance -0.0508)
				)
				(layer "B.Cu"
					(shape circle)
					(size 2.1844 2.1844)
				)
			)
		)
		(pad "GH1" thru_hole circle
			(at -2.54 -2.54)
			(size 2.286 2.286)
			(drill 1.6002)
			(layers "*.Cu" "*.Mask")
			(remove_unused_layers no)
			(net "SG")
			(padstack
				(mode front_inner_back)
				(layer "Inner"
					(shape circle)
					(size 2.286 2.286)
					(clearance -0.0508)
				)
				(layer "B.Cu"
					(shape circle)
					(size 2.286 2.286)
				)
			)
		)
		(pad "GH2" thru_hole circle
			(at 2.54 -2.54)
			(size 2.286 2.286)
			(drill 1.6002)
			(layers "*.Cu" "*.Mask")
			(remove_unused_layers no)
			(net "SG")
			(padstack
				(mode front_inner_back)
				(layer "Inner"
					(shape circle)
					(size 2.286 2.286)
					(clearance -0.0508)
				)
				(layer "B.Cu"
					(shape circle)
					(size 2.286 2.286)
				)
			)
		)
		(pad "GH3" thru_hole circle
			(at -2.54 2.54)
			(size 2.286 2.286)
			(drill 1.6002)
			(layers "*.Cu" "*.Mask")
			(remove_unused_layers no)
			(net "SG")
			(padstack
				(mode front_inner_back)
				(layer "Inner"
					(shape circle)
					(size 2.286 2.286)
					(clearance -0.0508)
				)
				(layer "B.Cu"
					(shape circle)
					(size 2.286 2.286)
				)
			)
		)
		(pad "GH4" thru_hole circle
			(at 2.54 2.54)
			(size 2.286 2.286)
			(drill 1.6002)
			(layers "*.Cu" "*.Mask")
			(remove_unused_layers no)
			(net "SG")
			(padstack
				(mode front_inner_back)
				(layer "Inner"
					(shape circle)
					(size 2.286 2.286)
					(clearance -0.0508)
				)
				(layer "B.Cu"
					(shape circle)
					(size 2.286 2.286)
				)
			)
		)
	)
)
